# T6G (Grand Teton) — schematic netlist excerpt (pin names and nets, part order shuffled) for the footprints in the layout excerpt that follows; sources: Cadence DE-HDL packaged netlist, KiCad conversion of 04192023_DAF0TMB3IC0_F0TG_MB_C_brd_V02_OCP.brd

J30  SCONN288_DDR506112002KQ  IO  pkg DDR288S_1-1VXC  page 101
  VIN_BULK0  = P12V_MEM_CPU1
  RFU0  = NC
  VIN_MGMT  = P3V3_AUX
  HSCL  = I3C_SPD_DDRD_CPU1_SCL
  HSDA  = I3C_SPD_DDRD_CPU1_SDA
  VSS0  = GND
  DQ0_A  = M_D_CPU1_SA_DQ<0>
  VSS1  = GND
  DQ1_A  = M_D_CPU1_SA_DQ<1>
  VSS2  = GND
  DQS0_A_T  = M_D_CPU1_SA_DQS_DP<0>
  DQS0_A_C  = M_D_CPU1_SA_DQS_DN<0>
  VSS3  = GND
  DQ4_A  = M_D_CPU1_SA_DQ<4>
  VSS4  = GND
  DQ5_A  = M_D_CPU1_SA_DQ<5>
  VSS5  = GND
  DQ8_A  = M_D_CPU1_SA_DQ<8>
  VSS6  = GND
  DQ9_A  = M_D_CPU1_SA_DQ<9>
  VSS7  = GND
  DQS1_A_T  = M_D_CPU1_SA_DQS_DP<1>
  DQS1_A_C  = M_D_CPU1_SA_DQS_DN<1>
  VSS8  = GND
  DQ12_A  = M_D_CPU1_SA_DQ<12>
  VSS9  = GND
  DQ13_A  = M_D_CPU1_SA_DQ<13>
  VSS10  = GND
  DQ16_A  = M_D_CPU1_SA_DQ<16>
  VSS11  = GND
  DQ17_A  = M_D_CPU1_SA_DQ<17>
  VSS12  = GND
  DQS2_A_T  = M_D_CPU1_SA_DQS_DP<2>
  DQS2_A_C  = M_D_CPU1_SA_DQS_DN<2>
  VSS13  = GND
  DQ20_A  = M_D_CPU1_SA_DQ<20>
  VSS14  = GND
  DQ21_A  = M_D_CPU1_SA_DQ<21>
  VSS15  = GND
  DQ24_A  = M_D_CPU1_SA_DQ<24>
  VSS16  = GND
  DQ25_A  = M_D_CPU1_SA_DQ<25>
  VSS17  = GND
  DQS3_A_T  = M_D_CPU1_SA_DQS_DP<3>
  DQS3_A_C  = M_D_CPU1_SA_DQS_DN<3>
  VSS18  = GND
  DQ28_A  = M_D_CPU1_SA_DQ<28>
  VSS19  = GND
  DQ29_A  = M_D_CPU1_SA_DQ<29>
  VSS20  = GND
  CB0_A  = M_D_CPU1_SA_CB<0>
  VSS21  = GND
  CB1_A  = M_D_CPU1_SA_CB<1>
  VSS22  = GND
  DQS4_A_T  = M_D_CPU1_SA_DQS_DP<4>
  DQS4_A_C  = M_D_CPU1_SA_DQS_DN<4>
  VSS23  = GND
  CB4_A  = M_D_CPU1_SA_CB<4>
  VSS24  = GND
  CB5_A  = M_D_CPU1_SA_CB<5>
  VSS25  = GND
  ALERT_N  = M_D_CPU1_ALERT_N
  VSS26  = GND
  CS0_A_N  = M_D_CPU1_SA_CS_N<0>
  VSS27  = GND
  CA0_A  = M_D_CPU1_SA_CA<0>
  VSS28  = GND
  CA2_A  = M_D_CPU1_SA_CA<2>
  VSS29  = GND
  CA4_A  = M_D_CPU1_SA_CA<4>
  VSS30  = GND
  CA6_A  = M_D_CPU1_SA_CA<6>
  VSS31  = GND
  PAR_A  = M_D_CPU1_SA_PAR
  VSS32  = GND
  CA0_B  = M_D_CPU1_SB_CA<0>
  VSS33  = GND
  CA2_B  = M_D_CPU1_SB_CA<2>
  VSS34  = GND
  CA4_B  = M_D_CPU1_SB_CA<4>
  VSS35  = GND
  CA6_B  = M_D_CPU1_SB_CA<6>
  VSS36  = GND
  CS0_B_N  = M_D_CPU1_SB_CS_N<0>
  VSS37  = GND
  \lbd||rsp_a_n\  = M_D_CPU1_SA_RSP<0>
  \lbs||rsp_b_n\  = M_D_CPU1_SB_RSP<0>
  VSS38  = GND
  CB4_B  = M_D_CPU1_SB_CB<4>
  VSS39  = GND
  CB5_B  = M_D_CPU1_SB_CB<5>
  VSS40  = GND
  \dqs9_b_t||tdqs9_b_t||dbi4_b_n\  = M_D_CPU1_SB_DQS_DP<9>
  \dqs9_b_c||tdqs9_b_c\  = M_D_CPU1_SB_DQS_DN<9>
  VSS41  = GND
  CB0_B  = M_D_CPU1_SB_CB<0>
  VSS42  = GND
  CB1_B  = M_D_CPU1_SB_CB<1>
  VSS43  = GND
  DQ0_B  = M_D_CPU1_SB_DQ<0>
  VSS44  = GND
  DQ1_B  = M_D_CPU1_SB_DQ<1>
  VSS45  = GND
  DQS0_B_T  = M_D_CPU1_SB_DQS_DP<0>
  DQS0_B_C  = M_D_CPU1_SB_DQS_DN<0>
  VSS46  = GND
  DQ4_B  = M_D_CPU1_SB_DQ<4>
  VSS47  = GND
  DQ5_B  = M_D_CPU1_SB_DQ<5>
  VSS48  = GND
  DQ8_B  = M_D_CPU1_SB_DQ<8>
  VSS49  = GND
  DQ9_B  = M_D_CPU1_SB_DQ<9>
  VSS50  = GND
  DQS1_B_T  = M_D_CPU1_SB_DQS_DP<1>
  DQS1_B_C  = M_D_CPU1_SB_DQS_DN<1>
  VSS51  = GND
  DQ12_B  = M_D_CPU1_SB_DQ<12>
  VSS52  = GND
  DQ13_B  = M_D_CPU1_SB_DQ<13>
  VSS53  = GND
  DQ16_B  = M_D_CPU1_SB_DQ<16>
  VSS54  = GND
  DQ17_B  = M_D_CPU1_SB_DQ<17>
  VSS55  = GND
  DQS2_B_T  = M_D_CPU1_SB_DQS_DP<2>
  DQS2_B_C  = M_D_CPU1_SB_DQS_DN<2>
  VSS56  = GND
  DQ20_B  = M_D_CPU1_SB_DQ<20>
  VSS57  = GND
  DQ21_B  = M_D_CPU1_SB_DQ<21>
  VSS58  = GND
  DQ24_B  = M_D_CPU1_SB_DQ<24>
  VSS59  = GND
  DQ25_B  = M_D_CPU1_SB_DQ<25>
  VSS60  = GND
  DQS3_B_T  = M_D_CPU1_SB_DQS_DP<3>
  DQS3_B_C  = M_D_CPU1_SB_DQS_DN<3>
  VSS61  = GND
  DQ28_B  = M_D_CPU1_SB_DQ<28>
  VSS62  = GND
  DQ29_B  = M_D_CPU1_SB_DQ<29>
  VSS63  = GND
  RFU1  = NC
  VIN_BULK1  = P12V_MEM_CPU1
  VIN_BULK2  = P12V_MEM_CPU1
  \pwr_good||fail_n\  = PWRGD_CHD_CPU1_DIMM
  HAS  = PD_CHD_CPU1_DIMM_SAA
  RFU2  = NC
  RFU3  = NC
  VSS64  = GND
  DQ2_A  = M_D_CPU1_SA_DQ<2>
  VSS65  = GND
  DQ3_A  = M_D_CPU1_SA_DQ<3>
  VSS66  = GND
  \dqs5_a_c||tdqs5_a_c||dqs5_a_t||tdqs5_a_t\  = M_D_CPU1_SA_DQS_DN<5>
  \dqs5_a_t||tdqs5_a_t\  = M_D_CPU1_SA_DQS_DP<5>
  VSS67  = GND
  DQ6_A  = M_D_CPU1_SA_DQ<6>
  VSS68  = GND
  DQ7_A  = M_D_CPU1_SA_DQ<7>
  VSS69  = GND
  DQ10_A  = M_D_CPU1_SA_DQ<10>
  VSS70  = GND
  DQ11_A  = M_D_CPU1_SA_DQ<11>
  VSS71  = GND
  \dqs6_a_c||tdqs6_a_c||dqs6_a_t||tdqs6_a_t\  = M_D_CPU1_SA_DQS_DN<6>
  \dqs6_a_t||tdqs6_a_t\  = M_D_CPU1_SA_DQS_DP<6>
  VSS72  = GND
  DQ14_A  = M_D_CPU1_SA_DQ<14>
  VSS73  = GND
  DQ15_A  = M_D_CPU1_SA_DQ<15>
  VSS74  = GND
  DQ18_A  = M_D_CPU1_SA_DQ<18>
  VSS75  = GND
  DQ19_A  = M_D_CPU1_SA_DQ<19>
  VSS76  = GND
  \dqs7_a_c||tdqs7_a_c\  = M_D_CPU1_SA_DQS_DN<7>
  \dqs7_a_t||tdqs7_a_t\  = M_D_CPU1_SA_DQS_DP<7>
  VSS77  = GND
  DQ22_A  = M_D_CPU1_SA_DQ<22>
  VSS78  = GND
  DQ23_A  = M_D_CPU1_SA_DQ<23>
  VSS79  = GND
  DQ26_A  = M_D_CPU1_SA_DQ<26>
  VSS80  = GND
  DQ27_A  = M_D_CPU1_SA_DQ<27>
  VSS81  = GND
  \dqs8_a_c||tdqs8_a_c\  = M_D_CPU1_SA_DQS_DN<8>
  \dqs8_a_t||tdqs8_a_t\  = M_D_CPU1_SA_DQS_DP<8>
  VSS82  = GND
  DQ30_A  = M_D_CPU1_SA_DQ<30>
  VSS83  = GND
  DQ31_A  = M_D_CPU1_SA_DQ<31>
  VSS84  = GND
  CB2_A  = M_D_CPU1_SA_CB<2>
  VSS85  = GND
  CB3_A  = M_D_CPU1_SA_CB<3>
  VSS86  = GND
  \dqs9_a_c||tdqs9_a_c\  = M_D_CPU1_SA_DQS_DN<9>
  \dqs9_a_t||tdqs9_a_t\  = M_D_CPU1_SA_DQS_DP<9>
  VSS87  = GND
  CB6_A  = M_D_CPU1_SA_CB<6>
  VSS88  = GND
  CB7_A  = M_D_CPU1_SA_CB<7>
  VSS89  = GND
  RESET_N  = M_D_CPU1_RESET_N
  VSS90  = GND
  CS1_A_N  = M_D_CPU1_SA_CS_N<1>
  VSS91  = GND
  CA1_A  = M_D_CPU1_SA_CA<1>
  VSS92  = GND
  CA3_A  = M_D_CPU1_SA_CA<3>
  VSS93  = GND
  CA5_A  = M_D_CPU1_SA_CA<5>
  VSS94  = GND
  CK_T  = M_D_CPU1_CLK_DP<0>
  CK_C  = M_D_CPU1_CLK_DN<0>
  VSS95  = GND
  RFU4  = NC
  CA1_B  = M_D_CPU1_SB_CA<1>
  VSS96  = GND
  CA3_B  = M_D_CPU1_SB_CA<3>
  VSS97  = GND
  CA5_B  = M_D_CPU1_SB_CA<5>
  VSS98  = GND
  PAR_B  = M_D_CPU1_SB_PAR
  VSS99  = GND
  CS1_B_N  = M_D_CPU1_SB_CS_N<1>
  VSS100  = GND
  RFU5  = NC
  RFU6  = NC
  VSS101  = GND
  CB6_B  = M_D_CPU1_SB_CB<6>
  VSS102  = GND
  CB7_B  = M_D_CPU1_SB_CB<7>
  VSS103  = GND
  DQS4_B_C  = M_D_CPU1_SB_DQS_DN<4>
  DQS4_B_T  = M_D_CPU1_SB_DQS_DP<4>
  VSS104  = GND
  CB2_B  = M_D_CPU1_SB_CB<2>
  VSS105  = GND
  CB3_B  = M_D_CPU1_SB_CB<3>
  VSS106  = GND
  DQ2_B  = M_D_CPU1_SB_DQ<2>
  VSS107  = GND
  DQ3_B  = M_D_CPU1_SB_DQ<3>
  VSS108  = GND
  \dqs5_b_c||tdqs5_b_c\  = M_D_CPU1_SB_DQS_DN<5>
  \dqs5_b_t||tdqs5_b_t\  = M_D_CPU1_SB_DQS_DP<5>
  VSS109  = GND
  DQ6_B  = M_D_CPU1_SB_DQ<6>
  VSS110  = GND
  DQ7_B  = M_D_CPU1_SB_DQ<7>
  VSS111  = GND
  DQ10_B  = M_D_CPU1_SB_DQ<10>
  VSS112  = GND
  DQ11_B  = M_D_CPU1_SB_DQ<11>
  VSS113  = GND
  \dqs6_b_c||tdqs6_b_c\  = M_D_CPU1_SB_DQS_DN<6>
  \dqs6_b_t||tdqs6_b_t\  = M_D_CPU1_SB_DQS_DP<6>
  VSS114  = GND
  DQ14_B  = M_D_CPU1_SB_DQ<14>
  VSS115  = GND
  DQ15_B  = M_D_CPU1_SB_DQ<15>
  VSS116  = GND
  DQ18_B  = M_D_CPU1_SB_DQ<18>
  VSS117  = GND
  DQ19_B  = M_D_CPU1_SB_DQ<19>
  VSS118  = GND
  \dqs7_b_c||tdqs7_b_c\  = M_D_CPU1_SB_DQS_DN<7>
  \dqs7_b_t||tdqs7_b_t\  = M_D_CPU1_SB_DQS_DP<7>
  VSS119  = GND
  DQ22_B  = M_D_CPU1_SB_DQ<22>
  VSS120  = GND
  DQ23_B  = M_D_CPU1_SB_DQ<23>
  VSS121  = GND
  DQ26_B  = M_D_CPU1_SB_DQ<26>
  VSS122  = GND
  DQ27_B  = M_D_CPU1_SB_DQ<27>
  VSS123  = GND
  \dqs8_b_c||tdqs8_b_c\  = M_D_CPU1_SB_DQS_DN<8>
  \dqs8_b_t||tdqs8_b_t\  = M_D_CPU1_SB_DQS_DP<8>
  VSS124  = GND
  DQ30_B  = M_D_CPU1_SB_DQ<30>
  VSS125  = GND
  DQ31_B  = M_D_CPU1_SB_DQ<31>
  VSS126  = GND
  G1  = GND
  G2  = GND
  G3  = GND

(kicad_pcb
	(version 20260206)
	(generator "pcbnew")
	(generator_version "10.0")
	(general
		(thickness 1.6)
		(legacy_teardrops no)
	)
	(paper "A4")
	(title_block
		(title "04192023_DAF0TMB3IC0_F0TG_MB_C_brd_V02_OCP.brd")
		(comment 1 "Grand Teton / footprint 3579 of 8354 (J30), pads 231-276 of 291")
	)
	(layers
		(0 "F.Cu" signal "TOP")
		(4 "In1.Cu" signal "GND")
		(6 "In2.Cu" signal "IN1")
		(8 "In3.Cu" signal "GND1")
		(10 "In4.Cu" signal "IN2")
		(12 "In5.Cu" signal "GND2")
		(14 "In6.Cu" signal "IN3")
		(16 "In7.Cu" signal "GND3")
		(18 "In8.Cu" signal "VCC")
		(20 "In9.Cu" signal "VCC1")
		(22 "In10.Cu" signal "GND4")
		(24 "In11.Cu" signal "IN4")
		(26 "In12.Cu" signal "GND5")
		(28 "In13.Cu" signal "IN5")
		(30 "In14.Cu" signal "GND6")
		(32 "In15.Cu" signal "IN6")
		(34 "In16.Cu" signal "GND7")
		(2 "B.Cu" signal "BOTTOM")
		(9 "F.Adhes" user "F.Adhesive")
		(11 "B.Adhes" user "B.Adhesive")
		(13 "F.Paste" user "Package Geometry/Pastemask Top")
		(15 "B.Paste" user "Package Geometry/Pastemask Bottom")
		(5 "F.SilkS" user "Ref Des/Silkscreen Top")
		(7 "B.SilkS" user "Ref Des/Silkscreen Bottom")
		(1 "F.Mask" user "Board Geometry/Soldermask Top")
		(3 "B.Mask" user "Board Geometry/Soldermask Bottom")
		(17 "Dwgs.User" user "User.Drawings")
		(19 "Cmts.User" user "User.Comments")
		(21 "Eco1.User" user "User.Eco1")
		(23 "Eco2.User" user "User.Eco2")
		(25 "Edge.Cuts" user "Board Geometry/Outline")
		(27 "Margin" user)
		(31 "F.CrtYd" user "Package Geometry/Place Bound Top")
		(29 "B.CrtYd" user "Package Geometry/Place Bound Bottom")
		(35 "F.Fab" user "Ref Des/Assembly Top")
		(33 "B.Fab" user "Ref Des/Assembly Bottom")
	)
	(footprint ""
		(layer "F.Cu")
		(at 34.74593 -255.560322 180)
		(property "Reference" "J30"
			(at 3.12293 -81.850992 0)
			(unlocked yes)
			(layer "F.SilkS")
			(effects
				(font
					(size 0.7874 0.5842)
					(thickness 0.1524)
				)
			)
		)
		(property "Value" ""
			(at 0 0 180)
			(layer "F.Fab")
			(effects
				(font
					(size 1.27 1.27)
				)
			)
		)
		(duplicate_pad_numbers_are_jumpers no)
		(pad "231" smd rect
			(at 2.050034 14.875002 90)
			(size 0.519938 1.4986)
			(layers "F.Cu" "F.Mask" "F.Paste")
			(net "Net_2303")
		)
		(pad "232" smd rect
			(at 2.050034 15.724886 90)
			(size 0.519938 1.4986)
			(layers "F.Cu" "F.Mask" "F.Paste")
			(net "Net_2304")
		)
		(pad "233" smd rect
			(at 2.050034 16.575024 90)
			(size 0.519938 1.4986)
			(layers "F.Cu" "F.Mask" "F.Paste")
			(net "GND")
		)
		(pad "234" smd rect
			(at 2.050034 17.424908 90)
			(size 0.519938 1.4986)
			(layers "F.Cu" "F.Mask" "F.Paste")
			(net "M_D_CPU1_SB_CB<6>")
		)
		(pad "235" smd rect
			(at 2.050034 18.275046 90)
			(size 0.519938 1.4986)
			(layers "F.Cu" "F.Mask" "F.Paste")
			(net "GND")
		)
		(pad "236" smd rect
			(at 2.050034 19.12493 90)
			(size 0.519938 1.4986)
			(layers "F.Cu" "F.Mask" "F.Paste")
			(net "M_D_CPU1_SB_CB<7>")
		)
		(pad "237" smd rect
			(at 2.050034 19.975068 90)
			(size 0.519938 1.4986)
			(layers "F.Cu" "F.Mask" "F.Paste")
			(net "GND")
		)
		(pad "238" smd rect
			(at 2.050034 20.824952 90)
			(size 0.519938 1.4986)
			(layers "F.Cu" "F.Mask" "F.Paste")
			(net "M_D_CPU1_SB_DQS_DN<4>")
		)
		(pad "239" smd rect
			(at 2.050034 21.67509 90)
			(size 0.519938 1.4986)
			(layers "F.Cu" "F.Mask" "F.Paste")
			(net "M_D_CPU1_SB_DQS_DP<4>")
		)
		(pad "240" smd rect
			(at 2.050034 22.524974 90)
			(size 0.519938 1.4986)
			(layers "F.Cu" "F.Mask" "F.Paste")
			(net "GND")
		)
		(pad "241" smd rect
			(at 2.050034 23.375112 90)
			(size 0.519938 1.4986)
			(layers "F.Cu" "F.Mask" "F.Paste")
			(net "M_D_CPU1_SB_CB<2>")
		)
		(pad "242" smd rect
			(at 2.050034 24.224996 90)
			(size 0.519938 1.4986)
			(layers "F.Cu" "F.Mask" "F.Paste")
			(net "GND")
		)
		(pad "243" smd rect
			(at 2.050034 25.07488 90)
			(size 0.519938 1.4986)
			(layers "F.Cu" "F.Mask" "F.Paste")
			(net "M_D_CPU1_SB_CB<3>")
		)
		(pad "244" smd rect
			(at 2.050034 25.925018 90)
			(size 0.519938 1.4986)
			(layers "F.Cu" "F.Mask" "F.Paste")
			(net "GND")
		)
		(pad "245" smd rect
			(at 2.050034 26.774902 90)
			(size 0.519938 1.4986)
			(layers "F.Cu" "F.Mask" "F.Paste")
			(net "M_D_CPU1_SB_DQ<2>")
		)
		(pad "246" smd rect
			(at 2.050034 27.62504 90)
			(size 0.519938 1.4986)
			(layers "F.Cu" "F.Mask" "F.Paste")
			(net "GND")
		)
		(pad "247" smd rect
			(at 2.050034 28.474924 90)
			(size 0.519938 1.4986)
			(layers "F.Cu" "F.Mask" "F.Paste")
			(net "M_D_CPU1_SB_DQ<3>")
		)
		(pad "248" smd rect
			(at 2.050034 29.325062 90)
			(size 0.519938 1.4986)
			(layers "F.Cu" "F.Mask" "F.Paste")
			(net "GND")
		)
		(pad "249" smd rect
			(at 2.050034 30.174946 90)
			(size 0.519938 1.4986)
			(layers "F.Cu" "F.Mask" "F.Paste")
			(net "M_D_CPU1_SB_DQS_DN<5>")
		)
		(pad "250" smd rect
			(at 2.050034 31.025084 90)
			(size 0.519938 1.4986)
			(layers "F.Cu" "F.Mask" "F.Paste")
			(net "M_D_CPU1_SB_DQS_DP<5>")
		)
		(pad "251" smd rect
			(at 2.050034 31.874968 90)
			(size 0.519938 1.4986)
			(layers "F.Cu" "F.Mask" "F.Paste")
			(net "GND")
		)
		(pad "252" smd rect
			(at 2.050034 32.725106 90)
			(size 0.519938 1.4986)
			(layers "F.Cu" "F.Mask" "F.Paste")
			(net "M_D_CPU1_SB_DQ<6>")
		)
		(pad "253" smd rect
			(at 2.050034 33.57499 90)
			(size 0.519938 1.4986)
			(layers "F.Cu" "F.Mask" "F.Paste")
			(net "GND")
		)
		(pad "254" smd rect
			(at 2.050034 34.425128 90)
			(size 0.519938 1.4986)
			(layers "F.Cu" "F.Mask" "F.Paste")
			(net "M_D_CPU1_SB_DQ<7>")
		)
		(pad "255" smd rect
			(at 2.050034 35.275012 90)
			(size 0.519938 1.4986)
			(layers "F.Cu" "F.Mask" "F.Paste")
			(net "GND")
		)
		(pad "256" smd rect
			(at 2.050034 36.124896 90)
			(size 0.519938 1.4986)
			(layers "F.Cu" "F.Mask" "F.Paste")
			(net "M_D_CPU1_SB_DQ<10>")
		)
		(pad "257" smd rect
			(at 2.050034 36.975034 90)
			(size 0.519938 1.4986)
			(layers "F.Cu" "F.Mask" "F.Paste")
			(net "GND")
		)
		(pad "258" smd rect
			(at 2.050034 37.824918 90)
			(size 0.519938 1.4986)
			(layers "F.Cu" "F.Mask" "F.Paste")
			(net "M_D_CPU1_SB_DQ<11>")
		)
		(pad "259" smd rect
			(at 2.050034 38.675056 90)
			(size 0.519938 1.4986)
			(layers "F.Cu" "F.Mask" "F.Paste")
			(net "GND")
		)
		(pad "260" smd rect
			(at 2.050034 39.52494 90)
			(size 0.519938 1.4986)
			(layers "F.Cu" "F.Mask" "F.Paste")
			(net "M_D_CPU1_SB_DQS_DN<6>")
		)
		(pad "261" smd rect
			(at 2.050034 40.375078 90)
			(size 0.519938 1.4986)
			(layers "F.Cu" "F.Mask" "F.Paste")
			(net "M_D_CPU1_SB_DQS_DP<6>")
		)
		(pad "262" smd rect
			(at 2.050034 41.224962 90)
			(size 0.519938 1.4986)
			(layers "F.Cu" "F.Mask" "F.Paste")
			(net "GND")
		)
		(pad "263" smd rect
			(at 2.050034 42.0751 90)
			(size 0.519938 1.4986)
			(layers "F.Cu" "F.Mask" "F.Paste")
			(net "M_D_CPU1_SB_DQ<14>")
		)
		(pad "264" smd rect
			(at 2.050034 42.924984 90)
			(size 0.519938 1.4986)
			(layers "F.Cu" "F.Mask" "F.Paste")
			(net "GND")
		)
		(pad "265" smd rect
			(at 2.050034 43.775122 90)
			(size 0.519938 1.4986)
			(layers "F.Cu" "F.Mask" "F.Paste")
			(net "M_D_CPU1_SB_DQ<15>")
		)
		(pad "266" smd rect
			(at 2.050034 44.625006 90)
			(size 0.519938 1.4986)
			(layers "F.Cu" "F.Mask" "F.Paste")
			(net "GND")
		)
		(pad "267" smd rect
			(at 2.050034 45.47489 90)
			(size 0.519938 1.4986)
			(layers "F.Cu" "F.Mask" "F.Paste")
			(net "M_D_CPU1_SB_DQ<18>")
		)
		(pad "268" smd rect
			(at 2.050034 46.325028 90)
			(size 0.519938 1.4986)
			(layers "F.Cu" "F.Mask" "F.Paste")
			(net "GND")
		)
		(pad "269" smd rect
			(at 2.050034 47.174912 90)
			(size 0.519938 1.4986)
			(layers "F.Cu" "F.Mask" "F.Paste")
			(net "M_D_CPU1_SB_DQ<19>")
		)
		(pad "270" smd rect
			(at 2.050034 48.02505 90)
			(size 0.519938 1.4986)
			(layers "F.Cu" "F.Mask" "F.Paste")
			(net "GND")
		)
		(pad "271" smd rect
			(at 2.050034 48.874934 90)
			(size 0.519938 1.4986)
			(layers "F.Cu" "F.Mask" "F.Paste")
			(net "M_D_CPU1_SB_DQS_DN<7>")
		)
		(pad "272" smd rect
			(at 2.050034 49.725072 90)
			(size 0.519938 1.4986)
			(layers "F.Cu" "F.Mask" "F.Paste")
			(net "M_D_CPU1_SB_DQS_DP<7>")
		)
		(pad "273" smd rect
			(at 2.050034 50.574956 90)
			(size 0.519938 1.4986)
			(layers "F.Cu" "F.Mask" "F.Paste")
			(net "GND")
		)
		(pad "274" smd rect
			(at 2.050034 51.425094 90)
			(size 0.519938 1.4986)
			(layers "F.Cu" "F.Mask" "F.Paste")
			(net "M_D_CPU1_SB_DQ<22>")
		)
		(pad "275" smd rect
			(at 2.050034 52.274978 90)
			(size 0.519938 1.4986)
			(layers "F.Cu" "F.Mask" "F.Paste")
			(net "GND")
		)
		(pad "276" smd rect
			(at 2.050034 53.125116 90)
			(size 0.519938 1.4986)
			(layers "F.Cu" "F.Mask" "F.Paste")
			(net "M_D_CPU1_SB_DQ<23>")
		)
	)
)
